(kicad_pcb
	(version 20241229)
	(generator "pcbnew")
	(generator_version "9.0")
	(general
		(thickness 1.62)
		(legacy_teardrops no)
	)
	(paper "A3")
	(title_block
		(title "COM Express 7 Baseboard")
		(date "2025-02-04")
		(rev "1.1.2")
		(company "Antmicro Ltd")
		(comment 1 "www.antmicro.com")
		(comment 9 "footprints 494-497 of 802")
	)
	(layers
		(0 "F.Cu" signal)
		(4 "In1.Cu" signal)
		(6 "In2.Cu" signal)
		(8 "In3.Cu" signal)
		(10 "In4.Cu" signal)
		(12 "In5.Cu" signal)
		(14 "In6.Cu" signal)
		(2 "B.Cu" signal)
		(9 "F.Adhes" user "F.Adhesive")
		(11 "B.Adhes" user "B.Adhesive")
		(13 "F.Paste" user)
		(15 "B.Paste" user)
		(5 "F.SilkS" user "F.Silkscreen")
		(7 "B.SilkS" user "B.Silkscreen")
		(1 "F.Mask" user)
		(3 "B.Mask" user)
		(17 "Dwgs.User" user "User.Drawings")
		(19 "Cmts.User" user "User.Comments")
		(21 "Eco1.User" user "User.Eco1")
		(23 "Eco2.User" user "User.Eco2")
		(25 "Edge.Cuts" user)
		(27 "Margin" user)
		(31 "F.CrtYd" user "F.Courtyard")
		(29 "B.CrtYd" user "B.Courtyard")
		(35 "F.Fab" user)
		(33 "B.Fab" user)
	)
	(footprint "antmicro-footprints:SOD-523"
		(layer "F.Cu")
		(at 113.2 91.31 -90)
		(property "Reference" "D2"
			(at -2.4 -0.5 90)
			(layer "F.SilkS")
			(effects
				(font
					(size 0.7 0.7)
					(thickness 0.15)
				)
				(justify right bottom)
			)
		)
		(property "Value" "PESD5Z5_0F"
			(at 0 1.499 90)
			(layer "F.Fab")
			(effects
				(font
					(size 0.7 0.7)
					(thickness 0.15)
				)
				(justify right bottom)
			)
		)
		(property "Datasheet" "https://assets.nexperia.com/documents/data-sheet/PESD5Z5_0.pdf"
			(at 0 0 270)
			(layer "F.Fab")
			(hide yes)
			(effects
				(font
					(size 1.27 1.27)
					(thickness 0.15)
				)
			)
		)
		(property "Author" "Antmicro"
			(at 21.89 204.51 0)
			(layer "F.Fab")
			(hide yes)
			(effects
				(font
					(size 1 1)
					(thickness 0.15)
				)
			)
		)
		(property "License" "Apache-2.0"
			(at 21.89 204.51 0)
			(layer "F.Fab")
			(hide yes)
			(effects
				(font
					(size 1 1)
					(thickness 0.15)
				)
			)
		)
		(property "MPN" "PESD5Z5.0F"
			(at 21.89 204.51 0)
			(layer "F.Fab")
			(hide yes)
			(effects
				(font
					(size 1 1)
					(thickness 0.15)
				)
			)
		)
		(property "Manufacturer" "Nexperia"
			(at 21.89 204.51 0)
			(layer "F.Fab")
			(hide yes)
			(effects
				(font
					(size 1 1)
					(thickness 0.15)
				)
			)
		)
		(property "Public" "False"
			(at 21.89 204.51 0)
			(layer "F.Fab")
			(hide yes)
			(effects
				(font
					(size 1 1)
					(thickness 0.15)
				)
			)
		)
		(sheetname "2xUSB3.0+RJ45")
		(sheetfile "usb3+rj45.kicad_sch")
		(attr smd)
		(fp_line
			(start -0.35 -0.5)
			(end -0.35 0.5)
			(stroke
				(width 0.15)
				(type solid)
			)
			(layer "F.SilkS")
		)
		(fp_rect
			(start -1 -0.6)
			(end 1 0.6)
			(stroke
				(width 0.05)
				(type solid)
			)
			(fill no)
			(layer "F.CrtYd")
		)
		(fp_line
			(start -0.652 0.423)
			(end 0.65 0.423)
			(stroke
				(width 0.15)
				(type solid)
			)
			(layer "F.Fab")
		)
		(fp_line
			(start -0.652 0.423)
			(end -0.652 -0.425)
			(stroke
				(width 0.15)
				(type solid)
			)
			(layer "F.Fab")
		)
		(fp_line
			(start -0.35 -0.4)
			(end -0.35 0.4)
			(stroke
				(width 0.15)
				(type solid)
			)
			(layer "F.Fab")
		)
		(fp_line
			(start -0.652 -0.425)
			(end 0.65 -0.425)
			(stroke
				(width 0.15)
				(type solid)
			)
			(layer "F.Fab")
		)
		(fp_line
			(start 0.65 -0.425)
			(end 0.65 0.423)
			(stroke
				(width 0.15)
				(type solid)
			)
			(layer "F.Fab")
		)
		(pad "1" smd roundrect
			(at -0.701 0 270)
			(size 0.5 0.6)
			(layers "F.Cu" "F.Mask" "F.Paste")
			(roundrect_rratio 0.25)
			(net 43 "/2xUSB3.0+RJ45/P2_VBUS")
			(pinfunction "C")
			(pintype "passive")
			(teardrops
				(best_length_ratio 0.2)
				(max_length 1)
				(best_width_ratio 0.9)
				(max_width 2)
				(curved_edges yes)
				(filter_ratio 0.9)
				(enabled yes)
				(allow_two_segments yes)
				(prefer_zone_connections yes)
			)
		)
		(pad "2" smd roundrect
			(at 0.699 0 270)
			(size 0.5 0.6)
			(layers "F.Cu" "F.Mask" "F.Paste")
			(roundrect_rratio 0.25)
			(net 1 "GND")
			(pinfunction "A")
			(pintype "passive")
			(teardrops
				(best_length_ratio 0.2)
				(max_length 1)
				(best_width_ratio 0.9)
				(max_width 2)
				(curved_edges yes)
				(filter_ratio 0.9)
				(enabled yes)
				(allow_two_segments yes)
				(prefer_zone_connections yes)
			)
		)
	)
	(footprint "antmicro-footprints:R_0402_1005Metric"
		(layer "F.Cu")
		(at 190.70861 77.152163 90)
		(descr "Resistor SMD 0402")
		(tags "resistor SMD 0402")
		(property "Reference" "R322"
			(at -1.9 -0.5 90)
			(layer "F.SilkS")
			(effects
				(font
					(size 0.7 0.7)
					(thickness 0.15)
				)
				(justify left bottom)
			)
		)
		(property "Value" "R_220R_0402"
			(at -1.011843 1.772047 90)
			(layer "F.Fab")
			(effects
				(font
					(size 0.7 0.7)
					(thickness 0.15)
				)
				(justify left bottom)
			)
		)
		(property "Datasheet" "https://www.bourns.com/docs/product-datasheets/cr.pdf"
			(at 0 0 90)
			(layer "F.Fab")
			(hide yes)
			(effects
				(font
					(size 1.27 1.27)
					(thickness 0.15)
				)
			)
		)
		(property "Author" "Antmicro"
			(at 267.860773 -113.556447 0)
			(layer "F.Fab")
			(hide yes)
			(effects
				(font
					(size 1 1)
					(thickness 0.15)
				)
			)
		)
		(property "License" "Apache-2.0"
			(at 267.860773 -113.556447 0)
			(layer "F.Fab")
			(hide yes)
			(effects
				(font
					(size 1 1)
					(thickness 0.15)
				)
			)
		)
		(property "MPN" "CR0402-FX-2200GLF"
			(at 267.860773 -113.556447 0)
			(layer "F.Fab")
			(hide yes)
			(effects
				(font
					(size 1 1)
					(thickness 0.15)
				)
			)
		)
		(property "Manufacturer" "Bourns"
			(at 267.860773 -113.556447 0)
			(layer "F.Fab")
			(hide yes)
			(effects
				(font
					(size 1 1)
					(thickness 0.15)
				)
			)
		)
		(property "Public" "False"
			(at 267.860773 -113.556447 0)
			(layer "F.Fab")
			(hide yes)
			(effects
				(font
					(size 1 1)
					(thickness 0.15)
				)
			)
		)
		(property "Tolerance" "1%"
			(at 267.860773 -113.556447 0)
			(layer "F.Fab")
			(hide yes)
			(effects
				(font
					(size 1 1)
					(thickness 0.15)
				)
			)
		)
		(property "Val" "220R"
			(at 267.860773 -113.556447 0)
			(layer "F.Fab")
			(hide yes)
			(effects
				(font
					(size 1 1)
					(thickness 0.15)
				)
			)
		)
		(sheetname "Power")
		(sheetfile "power.kicad_sch")
		(attr smd)
		(fp_rect
			(start -0.925 -0.47)
			(end 0.925 0.47)
			(stroke
				(width 0.05)
				(type default)
			)
			(fill no)
			(layer "F.CrtYd")
		)
		(fp_rect
			(start -0.5 -0.25)
			(end 0.5 0.25)
			(stroke
				(width 0.15)
				(type solid)
			)
			(fill no)
			(layer "F.Fab")
		)
		(pad "1" smd roundrect
			(at -0.48 0 90)
			(size 0.59 0.64)
			(layers "F.Cu" "F.Mask" "F.Paste")
			(roundrect_rratio 0.25)
			(net 1 "GND")
			(pintype "passive")
			(teardrops
				(best_length_ratio 0.2)
				(max_length 1)
				(best_width_ratio 0.9)
				(max_width 2)
				(curved_edges yes)
				(filter_ratio 0.9)
				(enabled yes)
				(allow_two_segments yes)
				(prefer_zone_connections yes)
			)
		)
		(pad "2" smd roundrect
			(at 0.48 0 90)
			(size 0.59 0.64)
			(layers "F.Cu" "F.Mask" "F.Paste")
			(roundrect_rratio 0.25)
			(net 982 "Net-(D30-C)")
			(pintype "passive")
			(teardrops
				(best_length_ratio 0.2)
				(max_length 1)
				(best_width_ratio 0.9)
				(max_width 2)
				(curved_edges yes)
				(filter_ratio 0.9)
				(enabled yes)
				(allow_two_segments yes)
				(prefer_zone_connections yes)
			)
		)
	)
	(footprint "antmicro-footprints:C_0402_1005Metric"
		(layer "F.Cu")
		(at 314.114999 121.939999 -90)
		(descr "Capacitor SMD 0402")
		(tags "capacitor SMD 0402")
		(property "Reference" "C47"
			(at 0.870001 -0.485001 90)
			(layer "F.SilkS")
			(effects
				(font
					(size 0.7 0.7)
					(thickness 0.15)
				)
				(justify right bottom)
			)
		)
		(property "Value" "C_100n_0402"
			(at -1.022927 2.155213 90)
			(layer "F.Fab")
			(effects
				(font
					(size 0.7 0.7)
					(thickness 0.15)
				)
				(justify right bottom)
			)
		)
		(property "Datasheet" "https://www.murata.com/products/productdetail?partno=GRM155R61H104KE14%23"
			(at 0 0 270)
			(layer "F.Fab")
			(hide yes)
			(effects
				(font
					(size 1.27 1.27)
					(thickness 0.15)
				)
			)
		)
		(property "Author" "Antmicro"
			(at 192.175 436.054998 0)
			(layer "F.Fab")
			(hide yes)
			(effects
				(font
					(size 1 1)
					(thickness 0.15)
				)
			)
		)
		(property "Dielectric" "X5R"
			(at 192.175 436.054998 0)
			(layer "F.Fab")
			(hide yes)
			(effects
				(font
					(size 1 1)
					(thickness 0.15)
				)
			)
		)
		(property "License" "Apache-2.0"
			(at 192.175 436.054998 0)
			(layer "F.Fab")
			(hide yes)
			(effects
				(font
					(size 1 1)
					(thickness 0.15)
				)
			)
		)
		(property "MPN" "GRM155R61H104KE14D"
			(at 192.175 436.054998 0)
			(layer "F.Fab")
			(hide yes)
			(effects
				(font
					(size 1 1)
					(thickness 0.15)
				)
			)
		)
		(property "Manufacturer" "Murata"
			(at 192.175 436.054998 0)
			(layer "F.Fab")
			(hide yes)
			(effects
				(font
					(size 1 1)
					(thickness 0.15)
				)
			)
		)
		(property "Public" "False"
			(at 192.175 436.054998 0)
			(layer "F.Fab")
			(hide yes)
			(effects
				(font
					(size 1 1)
					(thickness 0.15)
				)
			)
		)
		(property "Val" "100n"
			(at 192.175 436.054998 0)
			(layer "F.Fab")
			(hide yes)
			(effects
				(font
					(size 1 1)
					(thickness 0.15)
				)
			)
		)
		(property "Voltage" "50V"
			(at 192.175 436.054998 0)
			(layer "F.Fab")
			(hide yes)
			(effects
				(font
					(size 1 1)
					(thickness 0.15)
				)
			)
		)
		(sheetname "Power")
		(sheetfile "power.kicad_sch")
		(attr smd)
		(fp_rect
			(start -0.925 -0.47)
			(end 0.925 0.47)
			(stroke
				(width 0.05)
				(type default)
			)
			(fill no)
			(layer "F.CrtYd")
		)
		(fp_line
			(start -0.494 0.248)
			(end -0.494 -0.25)
			(stroke
				(width 0.15)
				(type solid)
			)
			(layer "F.Fab")
		)
		(fp_line
			(start 0.504 0.248)
			(end -0.494 0.248)
			(stroke
				(width 0.15)
				(type solid)
			)
			(layer "F.Fab")
		)
		(fp_line
			(start -0.494 -0.25)
			(end 0.504 -0.25)
			(stroke
				(width 0.15)
				(type solid)
			)
			(layer "F.Fab")
		)
		(fp_line
			(start 0.504 -0.25)
			(end 0.504 0.248)
			(stroke
				(width 0.15)
				(type solid)
			)
			(layer "F.Fab")
		)
		(pad "1" smd roundrect
			(at -0.48 0 270)
			(size 0.59 0.64)
			(layers "F.Cu" "F.Mask" "F.Paste")
			(roundrect_rratio 0.25)
			(net 66 "Net-(U18-BST)")
			(pintype "passive")
			(teardrops
				(best_length_ratio 0.2)
				(max_length 1)
				(best_width_ratio 0.9)
				(max_width 2)
				(curved_edges yes)
				(filter_ratio 0.9)
				(enabled yes)
				(allow_two_segments yes)
				(prefer_zone_connections yes)
			)
		)
		(pad "2" smd roundrect
			(at 0.48 0 270)
			(size 0.59 0.64)
			(layers "F.Cu" "F.Mask" "F.Paste")
			(roundrect_rratio 0.25)
			(net 67 "Net-(C47-Pad2)")
			(pintype "passive")
			(teardrops
				(best_length_ratio 0.2)
				(max_length 1)
				(best_width_ratio 0.9)
				(max_width 2)
				(curved_edges yes)
				(filter_ratio 0.9)
				(enabled yes)
				(allow_two_segments yes)
				(prefer_zone_connections yes)
			)
		)
	)
	(footprint "antmicro-footprints:SOT-23-3"
		(layer "F.Cu")
		(at 265.5 92.41 90)
		(property "Reference" "Q5"
			(at 1.45 0.45 180)
			(layer "F.SilkS")
			(effects
				(font
					(size 0.7 0.7)
					(thickness 0.15)
				)
				(justify left bottom)
			)
		)
		(property "Value" "BSS138-7-F"
			(at -1.9 2.7 90)
			(layer "F.Fab")
			(effects
				(font
					(size 0.7 0.7)
					(thickness 0.15)
				)
				(justify left bottom)
			)
		)
		(property "Datasheet" "https://www.diodes.com/assets/Datasheets/ds30144.pdf"
			(at 0 0 90)
			(layer "F.Fab")
			(hide yes)
			(effects
				(font
					(size 1.27 1.27)
					(thickness 0.15)
				)
			)
		)
		(property "Author" "Antmicro"
			(at 357.91 -173.09 0)
			(layer "F.Fab")
			(hide yes)
			(effects
				(font
					(size 1 1)
					(thickness 0.15)
				)
			)
		)
		(property "License" "Apache-2.0"
			(at 357.91 -173.09 0)
			(layer "F.Fab")
			(hide yes)
			(effects
				(font
					(size 1 1)
					(thickness 0.15)
				)
			)
		)
		(property "MPN" "BSS138-7-F"
			(at 357.91 -173.09 0)
			(layer "F.Fab")
			(hide yes)
			(effects
				(font
					(size 1 1)
					(thickness 0.15)
				)
			)
		)
		(property "Manufacturer" "Diodes Incorporated"
			(at 357.91 -173.09 0)
			(layer "F.Fab")
			(hide yes)
			(effects
				(font
					(size 1 1)
					(thickness 0.15)
				)
			)
		)
		(sheetname "Misc")
		(sheetfile "misc.kicad_sch")
		(attr smd)
		(fp_line
			(start 0.7 -1.5)
			(end -0.7 -1.5)
			(stroke
				(width 0.15)
				(type solid)
			)
			(layer "F.SilkS")
		)
		(fp_line
			(start -0.85 -1.35)
			(end -0.7 -1.5)
			(stroke
				(width 0.15)
				(type solid)
			)
			(layer "F.SilkS")
		)
		(fp_line
			(start -1.45 -1.35)
			(end -0.85 -1.35)
			(stroke
				(width 0.15)
				(type solid)
			)
			(layer "F.SilkS")
		)
		(fp_line
			(start 0.7 -0.4)
			(end 0.7 -1.5)
			(stroke
				(width 0.15)
				(type solid)
			)
			(layer "F.SilkS")
		)
		(fp_line
			(start 0.7 0.4)
			(end 0.7 1.5)
			(stroke
				(width 0.15)
				(type solid)
			)
			(layer "F.SilkS")
		)
		(fp_line
			(start 0.7 1.5)
			(end -0.7 1.5)
			(stroke
				(width 0.15)
				(type solid)
			)
			(layer "F.SilkS")
		)
		(fp_line
			(start -0.7 1.5)
			(end -0.7 1.35)
			(stroke
				(width 0.15)
				(type solid)
			)
			(layer "F.SilkS")
		)
		(fp_line
			(start 0.825 -1.6)
			(end 0.825 -0.45)
			(stroke
				(width 0.05)
				(type solid)
			)
			(layer "F.CrtYd")
		)
		(fp_line
			(start -0.9 -1.6)
			(end 0.825 -1.6)
			(stroke
				(width 0.05)
				(type solid)
			)
			(layer "F.CrtYd")
		)
		(fp_line
			(start -0.9 -1.6)
			(end -0.9 -1.4)
			(stroke
				(width 0.05)
				(type solid)
			)
			(layer "F.CrtYd")
		)
		(fp_line
			(start -0.9 -1.4)
			(end -1.75 -1.4)
			(stroke
				(width 0.05)
				(type solid)
			)
			(layer "F.CrtYd")
		)
		(fp_line
			(start -0.85 -0.5)
			(end -1.75 -0.5)
			(stroke
				(width 0.05)
				(type solid)
			)
			(layer "F.CrtYd")
		)
		(fp_line
			(start -1.75 -0.5)
			(end -1.75 -1.4)
			(stroke
				(width 0.05)
				(type solid)
			)
			(layer "F.CrtYd")
		)
		(fp_line
			(start 1.75 -0.45)
			(end 1.75 0.45)
			(stroke
				(width 0.05)
				(type solid)
			)
			(layer "F.CrtYd")
		)
		(fp_line
			(start 0.825 -0.45)
			(end 1.75 -0.45)
			(stroke
				(width 0.05)
				(type solid)
			)
			(layer "F.CrtYd")
		)
		(fp_line
			(start 1.75 0.45)
			(end 0.85 0.45)
			(stroke
				(width 0.05)
				(type solid)
			)
			(layer "F.CrtYd")
		)
		(fp_line
			(start 0.85 0.45)
			(end 0.85 1.65)
			(stroke
				(width 0.05)
				(type solid)
			)
			(layer "F.CrtYd")
		)
		(fp_line
			(start -0.85 0.5)
			(end -0.85 -0.5)
			(stroke
				(width 0.05)
				(type solid)
			)
			(layer "F.CrtYd")
		)
		(fp_line
			(start -1.75 0.5)
			(end -0.85 0.5)
			(stroke
				(width 0.05)
				(type solid)
			)
			(layer "F.CrtYd")
		)
		(fp_line
			(start -0.85 1.4)
			(end -1.75 1.4)
			(stroke
				(width 0.05)
				(type solid)
			)
			(layer "F.CrtYd")
		)
		(fp_line
			(start -1.75 1.4)
			(end -1.75 0.5)
			(stroke
				(width 0.05)
				(type solid)
			)
			(layer "F.CrtYd")
		)
		(fp_line
			(start 0.85 1.65)
			(end -0.85 1.65)
			(stroke
				(width 0.05)
				(type solid)
			)
			(layer "F.CrtYd")
		)
		(fp_line
			(start -0.85 1.65)
			(end -0.85 1.4)
			(stroke
				(width 0.05)
				(type solid)
			)
			(layer "F.CrtYd")
		)
		(fp_line
			(start -0.437 -1.526)
			(end 0.688 -1.526)
			(stroke
				(width 0.15)
				(type solid)
			)
			(layer "F.Fab")
		)
		(fp_line
			(start -0.437 -1.526)
			(end -0.712 -1.325)
			(stroke
				(width 0.15)
				(type solid)
			)
			(layer "F.Fab")
		)
		(fp_line
			(start -0.712 -1.325)
			(end -0.712 1.523)
			(stroke
				(width 0.15)
				(type solid)
			)
			(layer "F.Fab")
		)
		(fp_line
			(start 0.688 1.519)
			(end 0.688 -1.52)
			(stroke
				(width 0.15)
				(type solid)
			)
			(layer "F.Fab")
		)
		(fp_line
			(start -0.712 1.519)
			(end 0.688 1.519)
			(stroke
				(width 0.15)
				(type solid)
			)
			(layer "F.Fab")
		)
		(pad "1" smd roundrect
			(at -1.1 -0.951 90)
			(size 1 0.6)
			(layers "F.Cu" "F.Mask" "F.Paste")
			(roundrect_rratio 0.15)
			(net 528 "/Backplane/~{PERST}")
			(pinfunction "G")
			(pintype "bidirectional")
			(teardrops
				(best_length_ratio 0.2)
				(max_length 1)
				(best_width_ratio 0.9)
				(max_width 2)
				(curved_edges yes)
				(filter_ratio 0.9)
				(enabled yes)
				(allow_two_segments yes)
				(prefer_zone_connections yes)
			)
		)
		(pad "2" smd roundrect
			(at -1.1 0.949 90)
			(size 1 0.6)
			(layers "F.Cu" "F.Mask" "F.Paste")
			(roundrect_rratio 0.15)
			(net 1 "GND")
			(pinfunction "S")
			(pintype "bidirectional")
			(teardrops
				(best_length_ratio 0.2)
				(max_length 1)
				(best_width_ratio 0.9)
				(max_width 2)
				(curved_edges yes)
				(filter_ratio 0.9)
				(enabled yes)
				(allow_two_segments yes)
				(prefer_zone_connections yes)
			)
		)
		(pad "3" smd roundrect
			(at 1.1 -0.0005 90)
			(size 1 0.6)
			(layers "F.Cu" "F.Mask" "F.Paste")
			(roundrect_rratio 0.15)
			(net 538 "Net-(Q5-D)")
			(pinfunction "D")
			(pintype "bidirectional")
			(teardrops
				(best_length_ratio 0.2)
				(max_length 1)
				(best_width_ratio 0.9)
				(max_width 2)
				(curved_edges yes)
				(filter_ratio 0.9)
				(enabled yes)
				(allow_two_segments yes)
				(prefer_zone_connections yes)
			)
		)
	)
)
